# BASEBOARD_FAB2 (Tioga Pass) — schematic netlist excerpt (pin names and nets, part order shuffled) for the footprints in the layout excerpt that follows; sources: Cadence DE-HDL packaged netlist, KiCad conversion of Wiwynn_Tioga_Pass_MB.brd

R9B4  RES  49.9 1% CHIP  pkg 0402  page 167 : A = ISENSE_TMP421_1_E ; B = ISENSE_TMP421_1_DXP
R1C14  RES  0.0 5% CHIP  pkg 0402  page 206 : A = P3V3_STBY ; B = VR_PVCCIN_CPU1_VDD
C5G8  CAP_A  47UF 4V 20% X5R  pkg 0603V  page 217 : A = PVDDQ_ABC ; B = GND

(kicad_pcb
	(version 20260206)
	(generator "pcbnew")
	(generator_version "10.0")
	(general
		(thickness 1.6)
		(legacy_teardrops no)
	)
	(paper "A4")
	(title_block
		(title "Wiwynn_Tioga_Pass_MB.brd")
		(comment 1 "Tioga Pass / footprints 1493-1495 of 4770")
	)
	(layers
		(0 "F.Cu" signal "TOP")
		(4 "In1.Cu" signal "L2GND")
		(6 "In2.Cu" signal "L3")
		(8 "In3.Cu" signal "L4GND")
		(10 "In4.Cu" signal "L5")
		(12 "In5.Cu" signal "L6GND")
		(14 "In6.Cu" signal "L7VCC")
		(16 "In7.Cu" signal "L8VCC")
		(18 "In8.Cu" signal "L9GND")
		(20 "In9.Cu" signal "L10")
		(22 "In10.Cu" signal "L11GND")
		(24 "In11.Cu" signal "L12")
		(26 "In12.Cu" signal "L13GND")
		(2 "B.Cu" signal "BOTTOM")
		(9 "F.Adhes" user "F.Adhesive")
		(11 "B.Adhes" user "B.Adhesive")
		(13 "F.Paste" user "Package Geometry/Pastemask Top")
		(15 "B.Paste" user "Package Geometry/Pastemask Bottom")
		(5 "F.SilkS" user "Ref Des/Silkscreen Top")
		(7 "B.SilkS" user "Ref Des/Silkscreen Bottom")
		(1 "F.Mask" user "Board Geometry/Soldermask Top")
		(3 "B.Mask" user "Board Geometry/Soldermask Bottom")
		(17 "Dwgs.User" user "User.Drawings")
		(19 "Cmts.User" user "User.Comments")
		(21 "Eco1.User" user "User.Eco1")
		(23 "Eco2.User" user "User.Eco2")
		(25 "Edge.Cuts" user "Board Geometry/Outline")
		(27 "Margin" user)
		(31 "F.CrtYd" user "Package Geometry/Place Bound Top")
		(29 "B.CrtYd" user "Package Geometry/Place Bound Bottom")
		(35 "F.Fab" user "Ref Des/Assembly Top")
		(33 "B.Fab" user "Ref Des/Assembly Bottom")
	)
	(footprint ""
		(layer "F.Cu")
		(at 485.89184 -123.79706 90)
		(property "Reference" "R9B4"
			(at 0 0 90)
			(layer "F.SilkS")
			(hide yes)
			(effects
				(font
					(size 1.27 1.27)
				)
			)
		)
		(property "Value" ""
			(at 0 0 90)
			(layer "F.Fab")
			(effects
				(font
					(size 1.27 1.27)
				)
			)
		)
		(duplicate_pad_numbers_are_jumpers no)
		(fp_poly
			(pts
				(xy -0.2794 -0.1016) (xy 0.2794 -0.1016) (xy 0.2794 0.9906) (xy -0.2794 0.9906)
			)
			(stroke
				(width 0)
				(type default)
			)
			(fill no)
			(layer "F.CrtYd")
		)
		(fp_line
			(start 0.2794 -0.1016)
			(end -0.2794 -0.1016)
			(stroke
				(width 0.1)
				(type default)
			)
			(layer "F.Fab")
		)
		(fp_line
			(start -0.2794 -0.1016)
			(end -0.2794 0.9906)
			(stroke
				(width 0.1)
				(type default)
			)
			(layer "F.Fab")
		)
		(fp_line
			(start 0.2794 0.9906)
			(end 0.2794 -0.1016)
			(stroke
				(width 0.1)
				(type default)
			)
			(layer "F.Fab")
		)
		(fp_line
			(start -0.2794 0.9906)
			(end 0.2794 0.9906)
			(stroke
				(width 0.1)
				(type default)
			)
			(layer "F.Fab")
		)
		(pad "1" smd rect
			(at 0 0 90)
			(size 0.508 0.508)
			(layers "F.Cu" "F.Mask" "F.Paste")
			(net "ISENSE_TMP421_1_E")
		)
		(pad "2" smd rect
			(at 0 0.889 90)
			(size 0.508 0.508)
			(layers "F.Cu" "F.Mask" "F.Paste")
			(net "ISENSE_TMP421_1_DXP")
		)
		(zone
			(layer "F.Cu")
			(hatch none 0.5)
			(connect_pads
				(clearance 0)
			)
			(min_thickness 0.25)
			(keepout
				(tracks allowed)
				(vias not_allowed)
				(pads allowed)
				(copperpour not_allowed)
				(footprints allowed)
			)
			(placement
				(enabled no)
				(sheetname "")
			)
			(fill
				(thermal_gap 0.5)
				(thermal_bridge_width 0.5)
				(island_removal_mode 0)
			)
			(polygon
				(pts
					(xy 486.14584 -123.54306) (xy 486.14584 -124.05106) (xy 486.52684 -124.05106) (xy 486.52684 -123.54306)
				)
			)
		)
		(zone
			(layer "F.Cu")
			(hatch none 0.5)
			(connect_pads
				(clearance 0)
			)
			(min_thickness 0.25)
			(keepout
				(tracks not_allowed)
				(vias allowed)
				(pads allowed)
				(copperpour not_allowed)
				(footprints allowed)
			)
			(placement
				(enabled no)
				(sheetname "")
			)
			(fill
				(thermal_gap 0.5)
				(thermal_bridge_width 0.5)
				(island_removal_mode 0)
			)
			(polygon
				(pts
					(xy 486.52684 -123.54306) (xy 486.52684 -124.05106) (xy 486.14584 -124.05106) (xy 486.14584 -123.54306)
				)
			)
		)
	)
	(footprint ""
		(layer "F.Cu")
		(at 14.6812 -99.5934 90)
		(property "Reference" "R1C14"
			(at 0 0 90)
			(layer "F.SilkS")
			(hide yes)
			(effects
				(font
					(size 1.27 1.27)
				)
			)
		)
		(property "Value" ""
			(at 0 0 90)
			(layer "F.Fab")
			(effects
				(font
					(size 1.27 1.27)
				)
			)
		)
		(duplicate_pad_numbers_are_jumpers no)
		(fp_rect
			(start -0.2794 -0.1016)
			(end 0.2794 0.9906)
			(stroke
				(width 0)
				(type default)
			)
			(fill no)
			(layer "F.CrtYd")
		)
		(fp_line
			(start 0.2794 -0.1016)
			(end -0.2794 -0.1016)
			(stroke
				(width 0.1)
				(type default)
			)
			(layer "F.Fab")
		)
		(fp_line
			(start -0.2794 -0.1016)
			(end -0.2794 0.9906)
			(stroke
				(width 0.1)
				(type default)
			)
			(layer "F.Fab")
		)
		(fp_line
			(start 0.2794 0.9906)
			(end 0.2794 -0.1016)
			(stroke
				(width 0.1)
				(type default)
			)
			(layer "F.Fab")
		)
		(fp_line
			(start -0.2794 0.9906)
			(end 0.2794 0.9906)
			(stroke
				(width 0.1)
				(type default)
			)
			(layer "F.Fab")
		)
		(pad "1" smd rect
			(at 0 0 90)
			(size 0.508 0.508)
			(layers "F.Cu" "F.Mask" "F.Paste")
			(net "P3V3_STBY")
		)
		(pad "2" smd rect
			(at 0 0.889 90)
			(size 0.508 0.508)
			(layers "F.Cu" "F.Mask" "F.Paste")
			(net "VR_PVCCIN_CPU1_VDD")
		)
		(zone
			(layer "F.Cu")
			(hatch none 0.5)
			(connect_pads
				(clearance 0)
			)
			(min_thickness 0.25)
			(keepout
				(tracks allowed)
				(vias not_allowed)
				(pads allowed)
				(copperpour not_allowed)
				(footprints allowed)
			)
			(placement
				(enabled no)
				(sheetname "")
			)
			(fill
				(thermal_gap 0.5)
				(thermal_bridge_width 0.5)
				(island_removal_mode 0)
			)
			(polygon
				(pts
					(xy 14.9352 -99.3394) (xy 15.3162 -99.3394) (xy 15.3162 -99.8474) (xy 14.9352 -99.8474)
				)
			)
		)
		(zone
			(layer "F.Cu")
			(hatch none 0.5)
			(connect_pads
				(clearance 0)
			)
			(min_thickness 0.25)
			(keepout
				(tracks not_allowed)
				(vias allowed)
				(pads allowed)
				(copperpour not_allowed)
				(footprints allowed)
			)
			(placement
				(enabled no)
				(sheetname "")
			)
			(fill
				(thermal_gap 0.5)
				(thermal_bridge_width 0.5)
				(island_removal_mode 0)
			)
			(polygon
				(pts
					(xy 14.9352 -99.3394) (xy 15.3162 -99.3394) (xy 15.3162 -99.8474) (xy 14.9352 -99.8474)
				)
			)
		)
	)
	(footprint ""
		(layer "F.Cu")
		(at 276.000464 -12.954 90)
		(property "Reference" "C5G8"
			(at 1.848866 0.752348 90)
			(unlocked yes)
			(layer "F.SilkS")
			(effects
				(font
					(size 1.27 0.9652)
					(thickness 0.1524)
				)
			)
		)
		(property "Value" ""
			(at 0 0 90)
			(layer "F.Fab")
			(effects
				(font
					(size 1.27 1.27)
				)
			)
		)
		(duplicate_pad_numbers_are_jumpers no)
		(fp_rect
			(start -0.500126 1.598422)
			(end 0.500126 -0.201422)
			(stroke
				(width 0)
				(type default)
			)
			(fill no)
			(layer "F.CrtYd")
		)
		(fp_line
			(start 0.500126 -0.201422)
			(end 0.500126 1.598422)
			(stroke
				(width 0.1)
				(type default)
			)
			(layer "F.Fab")
		)
		(fp_line
			(start -0.500126 -0.201422)
			(end 0.500126 -0.201422)
			(stroke
				(width 0.1)
				(type default)
			)
			(layer "F.Fab")
		)
		(fp_line
			(start 0.500126 1.598422)
			(end -0.500126 1.598422)
			(stroke
				(width 0.1)
				(type default)
			)
			(layer "F.Fab")
		)
		(fp_line
			(start -0.500126 1.598422)
			(end -0.500126 -0.201422)
			(stroke
				(width 0.1)
				(type default)
			)
			(layer "F.Fab")
		)
		(pad "1" smd rect
			(at 0 0)
			(size 0.889 0.9906)
			(layers "F.Cu" "F.Mask" "F.Paste")
			(net "PVDDQ_ABC")
		)
		(pad "2" smd rect
			(at 0 1.397)
			(size 0.889 0.9906)
			(layers "F.Cu" "F.Mask" "F.Paste")
			(net "GND")
		)
		(zone
			(layer "F.Cu")
			(hatch none 0.5)
			(connect_pads
				(clearance 0)
			)
			(min_thickness 0.25)
			(keepout
				(tracks not_allowed)
				(vias allowed)
				(pads allowed)
				(copperpour not_allowed)
				(footprints allowed)
			)
			(placement
				(enabled no)
				(sheetname "")
			)
			(fill
				(thermal_gap 0.5)
				(thermal_bridge_width 0.5)
				(island_removal_mode 0)
			)
			(polygon
				(pts
					(xy 276.952964 -12.4587) (xy 276.952964 -13.4493) (xy 276.444964 -13.4493) (xy 276.444964 -12.4587)
				)
			)
		)
		(zone
			(layer "F.Cu")
			(hatch none 0.5)
			(connect_pads
				(clearance 0)
			)
			(min_thickness 0.25)
			(keepout
				(tracks allowed)
				(vias not_allowed)
				(pads allowed)
				(copperpour not_allowed)
				(footprints allowed)
			)
			(placement
				(enabled no)
				(sheetname "")
			)
			(fill
				(thermal_gap 0.5)
				(thermal_bridge_width 0.5)
				(island_removal_mode 0)
			)
			(polygon
				(pts
					(xy 276.952964 -12.4587) (xy 276.952964 -13.4493) (xy 276.444964 -13.4493) (xy 276.444964 -12.4587)
				)
			)
		)
	)
)
